# T6G (Grand Teton) — schematic netlist excerpt (pin names and nets, part order shuffled) for the footprints in the layout excerpt that follows; sources: Cadence DE-HDL packaged netlist, KiCad conversion of 04192023_DAF0TMB3IC0_F0TG_MB_C_brd_V02_OCP.brd

R8011  Q_RES  1K 1% EMPTY  pkg 0402LF  page 224 : A = PVDD18_S5_P1 ; B = PVDD11_S3_P1_OCP_N_R
R1422  Q_RES  100 1% CHIP  pkg 0402LF  page 85 : A = PWRGD_CPU0_PWROK ; B = PWRGD_CPU1_PWROK

(kicad_pcb
	(version 20260206)
	(generator "pcbnew")
	(generator_version "10.0")
	(general
		(thickness 1.6)
		(legacy_teardrops no)
	)
	(paper "A4")
	(title_block
		(title "04192023_DAF0TMB3IC0_F0TG_MB_C_brd_V02_OCP.brd")
		(comment 1 "Grand Teton / footprints 7091-7092 of 8354")
	)
	(layers
		(0 "F.Cu" signal "TOP")
		(4 "In1.Cu" signal "GND")
		(6 "In2.Cu" signal "IN1")
		(8 "In3.Cu" signal "GND1")
		(10 "In4.Cu" signal "IN2")
		(12 "In5.Cu" signal "GND2")
		(14 "In6.Cu" signal "IN3")
		(16 "In7.Cu" signal "GND3")
		(18 "In8.Cu" signal "VCC")
		(20 "In9.Cu" signal "VCC1")
		(22 "In10.Cu" signal "GND4")
		(24 "In11.Cu" signal "IN4")
		(26 "In12.Cu" signal "GND5")
		(28 "In13.Cu" signal "IN5")
		(30 "In14.Cu" signal "GND6")
		(32 "In15.Cu" signal "IN6")
		(34 "In16.Cu" signal "GND7")
		(2 "B.Cu" signal "BOTTOM")
		(9 "F.Adhes" user "F.Adhesive")
		(11 "B.Adhes" user "B.Adhesive")
		(13 "F.Paste" user "Package Geometry/Pastemask Top")
		(15 "B.Paste" user "Package Geometry/Pastemask Bottom")
		(5 "F.SilkS" user "Ref Des/Silkscreen Top")
		(7 "B.SilkS" user "Ref Des/Silkscreen Bottom")
		(1 "F.Mask" user "Board Geometry/Soldermask Top")
		(3 "B.Mask" user "Board Geometry/Soldermask Bottom")
		(17 "Dwgs.User" user "User.Drawings")
		(19 "Cmts.User" user "User.Comments")
		(21 "Eco1.User" user "User.Eco1")
		(23 "Eco2.User" user "User.Eco2")
		(25 "Edge.Cuts" user "Board Geometry/Outline")
		(27 "Margin" user)
		(31 "F.CrtYd" user "Package Geometry/Place Bound Top")
		(29 "B.CrtYd" user "Package Geometry/Place Bound Bottom")
		(35 "F.Fab" user "Ref Des/Assembly Top")
		(33 "B.Fab" user "Ref Des/Assembly Bottom")
	)
	(footprint ""
		(layer "B.Cu")
		(at 167.285162 -347.600016 90)
		(property "Reference" "R8011"
			(at 0 0 90)
			(layer "B.SilkS")
			(hide yes)
			(effects
				(font
					(size 1.27 1.27)
				)
				(justify mirror)
			)
		)
		(property "Value" ""
			(at 0 0 90)
			(layer "B.Fab")
			(effects
				(font
					(size 1.27 1.27)
				)
				(justify mirror)
			)
		)
		(duplicate_pad_numbers_are_jumpers no)
		(fp_line
			(start 0.7874 -0.4064)
			(end -0.7874 -0.4064)
			(stroke
				(width 0.1524)
				(type default)
			)
			(layer "B.SilkS")
		)
		(fp_line
			(start -0.7874 -0.4064)
			(end -0.7874 0.4064)
			(stroke
				(width 0.1524)
				(type default)
			)
			(layer "B.SilkS")
		)
		(fp_line
			(start 0.7874 0.4064)
			(end 0.7874 -0.4064)
			(stroke
				(width 0.1524)
				(type default)
			)
			(layer "B.SilkS")
		)
		(fp_line
			(start -0.7874 0.4064)
			(end 0.7874 0.4064)
			(stroke
				(width 0.1524)
				(type default)
			)
			(layer "B.SilkS")
		)
		(fp_line
			(start 0.67945 -0.305054)
			(end 0.12065 -0.305054)
			(stroke
				(width 0.1)
				(type default)
			)
			(layer "B.Fab")
		)
		(fp_line
			(start 0.12065 -0.305054)
			(end 0.12065 -0.2794)
			(stroke
				(width 0.1)
				(type default)
			)
			(layer "B.Fab")
		)
		(fp_line
			(start -0.12065 -0.3048)
			(end -0.67945 -0.3048)
			(stroke
				(width 0.1)
				(type default)
			)
			(layer "B.Fab")
		)
		(fp_line
			(start -0.67945 -0.3048)
			(end -0.67945 0.3048)
			(stroke
				(width 0.1)
				(type default)
			)
			(layer "B.Fab")
		)
		(fp_line
			(start 0.12065 -0.2794)
			(end -0.12065 -0.2794)
			(stroke
				(width 0.1)
				(type default)
			)
			(layer "B.Fab")
		)
		(fp_line
			(start -0.12065 -0.2794)
			(end -0.12065 -0.3048)
			(stroke
				(width 0.1)
				(type default)
			)
			(layer "B.Fab")
		)
		(fp_line
			(start 0.12065 0.2794)
			(end 0.12065 0.3048)
			(stroke
				(width 0.1)
				(type default)
			)
			(layer "B.Fab")
		)
		(fp_line
			(start -0.120396 0.2794)
			(end 0.12065 0.2794)
			(stroke
				(width 0.1)
				(type default)
			)
			(layer "B.Fab")
		)
		(fp_line
			(start 0.67945 0.3048)
			(end 0.67945 -0.305054)
			(stroke
				(width 0.1)
				(type default)
			)
			(layer "B.Fab")
		)
		(fp_line
			(start 0.12065 0.3048)
			(end 0.67945 0.3048)
			(stroke
				(width 0.1)
				(type default)
			)
			(layer "B.Fab")
		)
		(fp_line
			(start -0.120396 0.3048)
			(end -0.120396 0.2794)
			(stroke
				(width 0.1)
				(type default)
			)
			(layer "B.Fab")
		)
		(fp_line
			(start -0.67945 0.3048)
			(end -0.120396 0.3048)
			(stroke
				(width 0.1)
				(type default)
			)
			(layer "B.Fab")
		)
		(pad "1" smd circle
			(at 0.40005 0 270)
			(size 0 0)
			(layers "B.Cu" "B.Mask" "B.Paste")
			(net "PVDD18_S5_P1")
		)
		(pad "2" smd circle
			(at -0.40005 0 270)
			(size 0 0)
			(layers "B.Cu" "B.Mask" "B.Paste")
			(net "PVDD11_S3_P1_OCP_N_R")
		)
	)
	(footprint ""
		(layer "B.Cu")
		(at 179.7812 -133.111748 -90)
		(property "Reference" "R1422"
			(at 0 0 90)
			(layer "B.SilkS")
			(hide yes)
			(effects
				(font
					(size 1.27 1.27)
				)
				(justify mirror)
			)
		)
		(property "Value" ""
			(at 0 0 90)
			(layer "B.Fab")
			(effects
				(font
					(size 1.27 1.27)
				)
				(justify mirror)
			)
		)
		(duplicate_pad_numbers_are_jumpers no)
		(fp_line
			(start -0.7874 0.4064)
			(end 0.7874 0.4064)
			(stroke
				(width 0.1524)
				(type default)
			)
			(layer "B.SilkS")
		)
		(fp_line
			(start 0.7874 0.4064)
			(end 0.7874 -0.4064)
			(stroke
				(width 0.1524)
				(type default)
			)
			(layer "B.SilkS")
		)
		(fp_line
			(start -0.7874 -0.4064)
			(end -0.7874 0.4064)
			(stroke
				(width 0.1524)
				(type default)
			)
			(layer "B.SilkS")
		)
		(fp_line
			(start 0.7874 -0.4064)
			(end -0.7874 -0.4064)
			(stroke
				(width 0.1524)
				(type default)
			)
			(layer "B.SilkS")
		)
		(fp_line
			(start -0.67945 0.3048)
			(end -0.120396 0.3048)
			(stroke
				(width 0.1)
				(type default)
			)
			(layer "B.Fab")
		)
		(fp_line
			(start -0.120396 0.3048)
			(end -0.120396 0.2794)
			(stroke
				(width 0.1)
				(type default)
			)
			(layer "B.Fab")
		)
		(fp_line
			(start 0.12065 0.3048)
			(end 0.67945 0.3048)
			(stroke
				(width 0.1)
				(type default)
			)
			(layer "B.Fab")
		)
		(fp_line
			(start 0.67945 0.3048)
			(end 0.67945 -0.305054)
			(stroke
				(width 0.1)
				(type default)
			)
			(layer "B.Fab")
		)
		(fp_line
			(start -0.120396 0.2794)
			(end 0.12065 0.2794)
			(stroke
				(width 0.1)
				(type default)
			)
			(layer "B.Fab")
		)
		(fp_line
			(start 0.12065 0.2794)
			(end 0.12065 0.3048)
			(stroke
				(width 0.1)
				(type default)
			)
			(layer "B.Fab")
		)
		(fp_line
			(start -0.12065 -0.2794)
			(end -0.12065 -0.3048)
			(stroke
				(width 0.1)
				(type default)
			)
			(layer "B.Fab")
		)
		(fp_line
			(start 0.12065 -0.2794)
			(end -0.12065 -0.2794)
			(stroke
				(width 0.1)
				(type default)
			)
			(layer "B.Fab")
		)
		(fp_line
			(start -0.67945 -0.3048)
			(end -0.67945 0.3048)
			(stroke
				(width 0.1)
				(type default)
			)
			(layer "B.Fab")
		)
		(fp_line
			(start -0.12065 -0.3048)
			(end -0.67945 -0.3048)
			(stroke
				(width 0.1)
				(type default)
			)
			(layer "B.Fab")
		)
		(fp_line
			(start 0.12065 -0.305054)
			(end 0.12065 -0.2794)
			(stroke
				(width 0.1)
				(type default)
			)
			(layer "B.Fab")
		)
		(fp_line
			(start 0.67945 -0.305054)
			(end 0.12065 -0.305054)
			(stroke
				(width 0.1)
				(type default)
			)
			(layer "B.Fab")
		)
		(pad "1" smd circle
			(at 0.40005 0 90)
			(size 0 0)
			(layers "B.Cu" "B.Mask" "B.Paste")
			(net "PWRGD_CPU0_PWROK")
		)
		(pad "2" smd circle
			(at -0.40005 0 90)
			(size 0 0)
			(layers "B.Cu" "B.Mask" "B.Paste")
			(net "PWRGD_CPU1_PWROK")
		)
	)
)
